(kicad_pcb
	(version 20260206)
	(generator "pcbnew")
	(generator_version "10.0")
	(general
		(thickness 1.6)
		(legacy_teardrops no)
	)
	(paper "A4")
	(title_block
		(title "Bryce Canyon_F.DPB_16315-1-OCP.brd")
		(comment 1 "Bryce Canyon / footprints 313-319 of 2223")
	)
	(layers
		(0 "F.Cu" signal "TOP")
		(4 "In1.Cu" signal "L2GND")
		(6 "In2.Cu" signal "L3")
		(8 "In3.Cu" signal "L4GND")
		(10 "In4.Cu" signal "L5")
		(12 "In5.Cu" signal "L6VCC")
		(14 "In6.Cu" signal "L7VCC")
		(16 "In7.Cu" signal "L8")
		(18 "In8.Cu" signal "L9GND")
		(20 "In9.Cu" signal "L10")
		(22 "In10.Cu" signal "L11GND")
		(2 "B.Cu" signal "BOTTOM")
		(9 "F.Adhes" user "F.Adhesive")
		(11 "B.Adhes" user "B.Adhesive")
		(13 "F.Paste" user "Package Geometry/Pastemask Top")
		(15 "B.Paste" user "Package Geometry/Pastemask Bottom")
		(5 "F.SilkS" user "Ref Des/Silkscreen Top")
		(7 "B.SilkS" user "Ref Des/Silkscreen Bottom")
		(1 "F.Mask" user "Board Geometry/Soldermask Top")
		(3 "B.Mask" user "Board Geometry/Soldermask Bottom")
		(17 "Dwgs.User" user "User.Drawings")
		(19 "Cmts.User" user "User.Comments")
		(21 "Eco1.User" user "User.Eco1")
		(23 "Eco2.User" user "User.Eco2")
		(25 "Edge.Cuts" user "Board Geometry/Outline")
		(27 "Margin" user)
		(31 "F.CrtYd" user "Package Geometry/Place Bound Top")
		(29 "B.CrtYd" user "Package Geometry/Place Bound Bottom")
		(35 "F.Fab" user "Ref Des/Assembly Top")
		(33 "B.Fab" user "Ref Des/Assembly Bottom")
	)
	(footprint ""
		(layer "F.Cu")
		(at 54.546246 -46.065694 -90)
		(property "Reference" "R713"
			(at 0 0 270)
			(layer "F.SilkS")
			(hide yes)
			(effects
				(font
					(size 1.27 1.27)
				)
			)
		)
		(property "Value" "1KR2F-3-GP"
			(at 0.064008 -3.993896 270)
			(unlocked yes)
			(layer "F.Fab")
			(hide yes)
			(effects
				(font
					(size 1.016 1.016)
					(thickness 0.1524)
				)
			)
		)
		(property "Device Type" "R402H16"
			(at 0.064008 -5.517896 270)
			(unlocked yes)
			(layer "F.Fab")
			(hide yes)
			(effects
				(font
					(size 1.016 1.016)
					(thickness 0.1524)
				)
			)
		)
		(duplicate_pad_numbers_are_jumpers no)
		(fp_line
			(start -0.508 -0.9398)
			(end -0.508 0.9398)
			(stroke
				(width 0.1524)
				(type default)
			)
			(layer "F.SilkS")
		)
		(fp_line
			(start 0.508 -0.9398)
			(end -0.508 -0.9398)
			(stroke
				(width 0.1524)
				(type default)
			)
			(layer "F.SilkS")
		)
		(fp_rect
			(start -0.508 0.9398)
			(end 0.508 -0.9398)
			(stroke
				(width 0)
				(type default)
			)
			(fill no)
			(layer "F.CrtYd")
		)
		(fp_rect
			(start -0.508 0.9398)
			(end 0.508 -0.9398)
			(stroke
				(width 0)
				(type default)
			)
			(fill no)
			(layer "F.Fab")
		)
		(pad "1" smd custom
			(at 0 -0.4445 270)
			(size 0.1397 0.1397)
			(layers "F.Cu" "F.Mask" "F.Paste")
			(net "P3V3_STBY_A")
			(options
				(clearance outline)
				(anchor circle)
			)
			(primitives
				(gr_poly
					(pts
						(arc
							(start -0.1778 -0.2794)
							(mid -0.249642 -0.249642)
							(end -0.2794 -0.1778)
						)
						(arc
							(start -0.2794 0.1778)
							(mid -0.249642 0.249642)
							(end -0.1778 0.2794)
						)
						(arc
							(start 0.1778 0.2794)
							(mid 0.249642 0.249642)
							(end 0.2794 0.1778)
						)
						(arc
							(start 0.2794 -0.1778)
							(mid 0.249642 -0.249642)
							(end 0.1778 -0.2794)
						)
					)
					(width 0)
					(fill yes)
				)
			)
		)
		(pad "2" smd custom
			(at 0 0.4445 270)
			(size 0.1397 0.1397)
			(layers "F.Cu" "F.Mask" "F.Paste")
			(net "SW_PWR_R_HDD25")
			(options
				(clearance outline)
				(anchor circle)
			)
			(primitives
				(gr_poly
					(pts
						(arc
							(start -0.1778 -0.2794)
							(mid -0.249642 -0.249642)
							(end -0.2794 -0.1778)
						)
						(arc
							(start -0.2794 0.1778)
							(mid -0.249642 0.249642)
							(end -0.1778 0.2794)
						)
						(arc
							(start 0.1778 0.2794)
							(mid 0.249642 0.249642)
							(end 0.2794 0.1778)
						)
						(arc
							(start 0.2794 -0.1778)
							(mid 0.249642 -0.249642)
							(end 0.1778 -0.2794)
						)
					)
					(width 0)
					(fill yes)
				)
			)
		)
	)
	(footprint ""
		(layer "F.Cu")
		(at 322.260468 -242.210844)
		(property "Reference" "R242"
			(at 0 0 0)
			(layer "F.SilkS")
			(hide yes)
			(effects
				(font
					(size 1.27 1.27)
				)
			)
		)
		(property "Value" "91R3F-1-GP"
			(at -0.0254 -2.5146 0)
			(unlocked yes)
			(layer "F.Fab")
			(hide yes)
			(effects
				(font
					(size 1.016 1.016)
					(thickness 0.1524)
				)
			)
		)
		(property "Device Type" "R603H22"
			(at -0.0254 -4.0386 0)
			(unlocked yes)
			(layer "F.Fab")
			(hide yes)
			(effects
				(font
					(size 1.016 1.016)
					(thickness 0.1524)
				)
			)
		)
		(duplicate_pad_numbers_are_jumpers no)
		(fp_line
			(start -0.4826 0)
			(end -0.2032 0)
			(stroke
				(width 0.2032)
				(type default)
			)
			(layer "F.SilkS")
		)
		(fp_line
			(start 0.2032 0)
			(end 0.4826 0)
			(stroke
				(width 0.2032)
				(type default)
			)
			(layer "F.SilkS")
		)
		(fp_rect
			(start -0.5842 1.3335)
			(end 0.5842 -1.3335)
			(stroke
				(width 0)
				(type default)
			)
			(fill no)
			(layer "F.CrtYd")
		)
		(fp_rect
			(start -0.5842 1.3335)
			(end 0.5842 -1.3335)
			(stroke
				(width 0)
				(type default)
			)
			(fill no)
			(layer "F.Fab")
		)
		(pad "1" smd custom
			(at 0 -0.762)
			(size 0.2159 0.2159)
			(layers "F.Cu" "F.Mask" "F.Paste")
			(net "P5V_A_3")
			(options
				(clearance outline)
				(anchor circle)
			)
			(primitives
				(gr_poly
					(pts
						(arc
							(start -0.3302 -0.4318)
							(mid -0.402042 -0.402042)
							(end -0.4318 -0.3302)
						)
						(arc
							(start -0.4318 0.3302)
							(mid -0.402042 0.402042)
							(end -0.3302 0.4318)
						)
						(arc
							(start 0.3302 0.4318)
							(mid 0.402042 0.402042)
							(end 0.4318 0.3302)
						)
						(arc
							(start 0.4318 -0.3302)
							(mid 0.402042 -0.402042)
							(end 0.3302 -0.4318)
						)
					)
					(width 0)
					(fill yes)
				)
			)
		)
		(pad "2" smd custom
			(at 0 0.762)
			(size 0.2159 0.2159)
			(layers "F.Cu" "F.Mask" "F.Paste")
			(net "DRV_ACT_6")
			(options
				(clearance outline)
				(anchor circle)
			)
			(primitives
				(gr_poly
					(pts
						(arc
							(start -0.3302 -0.4318)
							(mid -0.402042 -0.402042)
							(end -0.4318 -0.3302)
						)
						(arc
							(start -0.4318 0.3302)
							(mid -0.402042 0.402042)
							(end -0.3302 0.4318)
						)
						(arc
							(start 0.3302 0.4318)
							(mid 0.402042 0.402042)
							(end 0.4318 0.3302)
						)
						(arc
							(start 0.4318 -0.3302)
							(mid 0.402042 -0.402042)
							(end 0.3302 -0.4318)
						)
					)
					(width 0)
					(fill yes)
				)
			)
		)
	)
	(footprint ""
		(layer "F.Cu")
		(at 302.3108 -74.7776)
		(property "Reference" "R357"
			(at 0 0 0)
			(layer "F.SilkS")
			(hide yes)
			(effects
				(font
					(size 1.27 1.27)
				)
			)
		)
		(property "Value" "0R2J-2-GP"
			(at 0.064008 -3.993896 0)
			(unlocked yes)
			(layer "F.Fab")
			(hide yes)
			(effects
				(font
					(size 1.016 1.016)
					(thickness 0.1524)
				)
			)
		)
		(property "Device Type" "R402H16"
			(at 0.064008 -5.517896 0)
			(unlocked yes)
			(layer "F.Fab")
			(hide yes)
			(effects
				(font
					(size 1.016 1.016)
					(thickness 0.1524)
				)
			)
		)
		(duplicate_pad_numbers_are_jumpers no)
		(fp_line
			(start -0.508 -0.9398)
			(end -0.508 0.9398)
			(stroke
				(width 0.1524)
				(type default)
			)
			(layer "F.SilkS")
		)
		(fp_line
			(start 0.508 -0.9398)
			(end -0.508 -0.9398)
			(stroke
				(width 0.1524)
				(type default)
			)
			(layer "F.SilkS")
		)
		(fp_rect
			(start -0.508 0.9398)
			(end 0.508 -0.9398)
			(stroke
				(width 0)
				(type default)
			)
			(fill no)
			(layer "F.CrtYd")
		)
		(fp_rect
			(start -0.508 0.9398)
			(end 0.508 -0.9398)
			(stroke
				(width 0)
				(type default)
			)
			(fill no)
			(layer "F.Fab")
		)
		(pad "1" smd custom
			(at 0 -0.4445)
			(size 0.1397 0.1397)
			(layers "F.Cu" "F.Mask" "F.Paste")
			(net "SLOT1_SVR_ID0_GPIO0")
			(options
				(clearance outline)
				(anchor circle)
			)
			(primitives
				(gr_poly
					(pts
						(arc
							(start -0.1778 -0.2794)
							(mid -0.249642 -0.249642)
							(end -0.2794 -0.1778)
						)
						(arc
							(start -0.2794 0.1778)
							(mid -0.249642 0.249642)
							(end -0.1778 0.2794)
						)
						(arc
							(start 0.1778 0.2794)
							(mid 0.249642 0.249642)
							(end 0.2794 0.1778)
						)
						(arc
							(start 0.2794 -0.1778)
							(mid 0.249642 -0.249642)
							(end 0.1778 -0.2794)
						)
					)
					(width 0)
					(fill yes)
				)
			)
		)
		(pad "2" smd custom
			(at 0 0.4445)
			(size 0.1397 0.1397)
			(layers "F.Cu" "F.Mask" "F.Paste")
			(net "COMP_B_BMC_B_SPARE_0")
			(options
				(clearance outline)
				(anchor circle)
			)
			(primitives
				(gr_poly
					(pts
						(arc
							(start -0.1778 -0.2794)
							(mid -0.249642 -0.249642)
							(end -0.2794 -0.1778)
						)
						(arc
							(start -0.2794 0.1778)
							(mid -0.249642 0.249642)
							(end -0.1778 0.2794)
						)
						(arc
							(start 0.1778 0.2794)
							(mid 0.249642 0.249642)
							(end 0.2794 0.1778)
						)
						(arc
							(start 0.2794 -0.1778)
							(mid 0.249642 -0.249642)
							(end 0.1778 -0.2794)
						)
					)
					(width 0)
					(fill yes)
				)
			)
		)
	)
	(footprint ""
		(layer "F.Cu")
		(at 241.6048 -260.5532 180)
		(property "Reference" "R43"
			(at 0 0 180)
			(layer "F.SilkS")
			(hide yes)
			(effects
				(font
					(size 1.27 1.27)
				)
			)
		)
		(property "Value" "0R2J-2-GP"
			(at 0.064008 -3.993896 180)
			(unlocked yes)
			(layer "F.Fab")
			(hide yes)
			(effects
				(font
					(size 1.016 1.016)
					(thickness 0.1524)
				)
			)
		)
		(property "Device Type" "R402H16"
			(at 0.064008 -5.517896 180)
			(unlocked yes)
			(layer "F.Fab")
			(hide yes)
			(effects
				(font
					(size 1.016 1.016)
					(thickness 0.1524)
				)
			)
		)
		(duplicate_pad_numbers_are_jumpers no)
		(fp_line
			(start 0.508 -0.9398)
			(end -0.508 -0.9398)
			(stroke
				(width 0.1524)
				(type default)
			)
			(layer "F.SilkS")
		)
		(fp_line
			(start -0.508 -0.9398)
			(end -0.508 0.9398)
			(stroke
				(width 0.1524)
				(type default)
			)
			(layer "F.SilkS")
		)
		(fp_rect
			(start -0.508 0.9398)
			(end 0.508 -0.9398)
			(stroke
				(width 0)
				(type default)
			)
			(fill no)
			(layer "F.CrtYd")
		)
		(fp_rect
			(start -0.508 0.9398)
			(end 0.508 -0.9398)
			(stroke
				(width 0)
				(type default)
			)
			(fill no)
			(layer "F.Fab")
		)
		(pad "1" smd custom
			(at 0 -0.4445 180)
			(size 0.1397 0.1397)
			(layers "F.Cu" "F.Mask" "F.Paste")
			(net "IO_EXP5_SCL")
			(options
				(clearance outline)
				(anchor circle)
			)
			(primitives
				(gr_poly
					(pts
						(arc
							(start -0.1778 -0.2794)
							(mid -0.249642 -0.249642)
							(end -0.2794 -0.1778)
						)
						(arc
							(start -0.2794 0.1778)
							(mid -0.249642 0.249642)
							(end -0.1778 0.2794)
						)
						(arc
							(start 0.1778 0.2794)
							(mid 0.249642 0.249642)
							(end 0.2794 0.1778)
						)
						(arc
							(start 0.2794 -0.1778)
							(mid 0.249642 -0.249642)
							(end 0.1778 -0.2794)
						)
					)
					(width 0)
					(fill yes)
				)
			)
		)
		(pad "2" smd custom
			(at 0 0.4445 180)
			(size 0.1397 0.1397)
			(layers "F.Cu" "F.Mask" "F.Paste")
			(net "I2C_DRIVE_A_INS_SCL")
			(options
				(clearance outline)
				(anchor circle)
			)
			(primitives
				(gr_poly
					(pts
						(arc
							(start -0.1778 -0.2794)
							(mid -0.249642 -0.249642)
							(end -0.2794 -0.1778)
						)
						(arc
							(start -0.2794 0.1778)
							(mid -0.249642 0.249642)
							(end -0.1778 0.2794)
						)
						(arc
							(start 0.1778 0.2794)
							(mid 0.249642 0.249642)
							(end 0.2794 0.1778)
						)
						(arc
							(start 0.2794 -0.1778)
							(mid 0.249642 -0.249642)
							(end 0.1778 -0.2794)
						)
					)
					(width 0)
					(fill yes)
				)
			)
		)
	)
	(footprint ""
		(layer "F.Cu")
		(at 251.097542 -383.085848 180)
		(property "Reference" "R1140"
			(at 0 0 180)
			(layer "F.SilkS")
			(hide yes)
			(effects
				(font
					(size 1.27 1.27)
				)
			)
		)
		(property "Value" "100R2D-GP"
			(at 0.064008 -3.993896 180)
			(unlocked yes)
			(layer "F.Fab")
			(hide yes)
			(effects
				(font
					(size 1.016 1.016)
					(thickness 0.1524)
				)
			)
		)
		(property "Device Type" "R402H14"
			(at 0.064008 -5.517896 180)
			(unlocked yes)
			(layer "F.Fab")
			(hide yes)
			(effects
				(font
					(size 1.016 1.016)
					(thickness 0.1524)
				)
			)
		)
		(duplicate_pad_numbers_are_jumpers no)
		(fp_line
			(start 0.508 -0.9398)
			(end -0.508 -0.9398)
			(stroke
				(width 0.1524)
				(type default)
			)
			(layer "F.SilkS")
		)
		(fp_line
			(start -0.508 -0.9398)
			(end -0.508 0.9398)
			(stroke
				(width 0.1524)
				(type default)
			)
			(layer "F.SilkS")
		)
		(fp_rect
			(start -0.508 0.9398)
			(end 0.508 -0.9398)
			(stroke
				(width 0)
				(type default)
			)
			(fill no)
			(layer "F.CrtYd")
		)
		(fp_rect
			(start -0.508 0.9398)
			(end 0.508 -0.9398)
			(stroke
				(width 0)
				(type default)
			)
			(fill no)
			(layer "F.Fab")
		)
		(pad "1" smd custom
			(at 0 -0.4445 180)
			(size 0.1397 0.1397)
			(layers "F.Cu" "F.Mask" "F.Paste")
			(net "GND")
			(options
				(clearance outline)
				(anchor circle)
			)
			(primitives
				(gr_poly
					(pts
						(arc
							(start -0.1778 -0.2794)
							(mid -0.249642 -0.249642)
							(end -0.2794 -0.1778)
						)
						(arc
							(start -0.2794 0.1778)
							(mid -0.249642 0.249642)
							(end -0.1778 0.2794)
						)
						(arc
							(start 0.1778 0.2794)
							(mid 0.249642 0.249642)
							(end 0.2794 0.1778)
						)
						(arc
							(start 0.2794 -0.1778)
							(mid 0.249642 -0.249642)
							(end 0.1778 -0.2794)
						)
					)
					(width 0)
					(fill yes)
				)
			)
		)
		(pad "2" smd custom
			(at 0 0.4445 180)
			(size 0.1397 0.1397)
			(layers "F.Cu" "F.Mask" "F.Paste")
			(net "MB3_TEMP_E")
			(options
				(clearance outline)
				(anchor circle)
			)
			(primitives
				(gr_poly
					(pts
						(arc
							(start -0.1778 -0.2794)
							(mid -0.249642 -0.249642)
							(end -0.2794 -0.1778)
						)
						(arc
							(start -0.2794 0.1778)
							(mid -0.249642 0.249642)
							(end -0.1778 0.2794)
						)
						(arc
							(start 0.1778 0.2794)
							(mid 0.249642 0.249642)
							(end 0.2794 0.1778)
						)
						(arc
							(start 0.2794 -0.1778)
							(mid 0.249642 -0.249642)
							(end 0.1778 -0.2794)
						)
					)
					(width 0)
					(fill yes)
				)
			)
		)
	)
	(footprint ""
		(layer "F.Cu")
		(at 369.176554 -127.729234 180)
		(property "Reference" "Q283"
			(at 0 0 180)
			(layer "F.SilkS")
			(hide yes)
			(effects
				(font
					(size 1.27 1.27)
				)
			)
		)
		(property "Value" "SSM3K324R-GP"
			(at 0.127 -8.9662 180)
			(unlocked yes)
			(layer "F.Fab")
			(hide yes)
			(effects
				(font
					(size 1.016 1.016)
					(thickness 0.1524)
				)
			)
		)
		(property "Device Type" "SOT23DGS2D4H35"
			(at 0.127 -10.4902 180)
			(unlocked yes)
			(layer "F.Fab")
			(hide yes)
			(effects
				(font
					(size 1.016 1.016)
					(thickness 0.1524)
				)
			)
		)
		(duplicate_pad_numbers_are_jumpers no)
		(fp_line
			(start 1.651 1.778)
			(end 1.651 -1.778)
			(stroke
				(width 0.1524)
				(type default)
			)
			(layer "F.SilkS")
		)
		(fp_line
			(start 1.651 -1.778)
			(end -1.651 -1.778)
			(stroke
				(width 0.1524)
				(type default)
			)
			(layer "F.SilkS")
		)
		(fp_line
			(start -1.651 1.778)
			(end 1.651 1.778)
			(stroke
				(width 0.1524)
				(type default)
			)
			(layer "F.SilkS")
		)
		(fp_line
			(start -1.651 -1.778)
			(end -1.651 1.778)
			(stroke
				(width 0.1524)
				(type default)
			)
			(layer "F.SilkS")
		)
		(fp_poly
			(pts
				(xy -1.778 1.8796) (xy -1.778 -1.8796) (xy 1.778 -1.8796) (xy 1.778 1.8796)
			)
			(stroke
				(width 0)
				(type default)
			)
			(fill no)
			(layer "F.CrtYd")
		)
		(fp_poly
			(pts
				(xy -1.778 1.8796) (xy -1.778 -1.8796) (xy 1.778 -1.8796) (xy 1.778 1.8796)
			)
			(stroke
				(width 0)
				(type default)
			)
			(fill no)
			(layer "F.Fab")
		)
		(pad "D" smd custom
			(at 0 -0.9525 180)
			(size 0.1905 0.1905)
			(layers "F.Cu" "F.Mask" "F.Paste")
			(net "DRV_ACT_20_N")
			(options
				(clearance outline)
				(anchor circle)
			)
			(primitives
				(gr_poly
					(pts
						(arc
							(start -0.1778 0.5715)
							(mid -0.321484 0.511984)
							(end -0.381 0.3683)
						)
						(arc
							(start -0.381 -0.3683)
							(mid -0.321484 -0.511984)
							(end -0.1778 -0.5715)
						)
						(arc
							(start 0.1778 -0.5715)
							(mid 0.321484 -0.511984)
							(end 0.381 -0.3683)
						)
						(arc
							(start 0.381 0.3683)
							(mid 0.321484 0.511984)
							(end 0.1778 0.5715)
						)
					)
					(width 0)
					(fill yes)
				)
			)
		)
		(pad "G" smd custom
			(at -0.98425 0.9525 180)
			(size 0.1905 0.1905)
			(layers "F.Cu" "F.Mask" "F.Paste")
			(net "DRIVE_A_20_ACT")
			(options
				(clearance outline)
				(anchor circle)
			)
			(primitives
				(gr_poly
					(pts
						(arc
							(start -0.1778 0.5715)
							(mid -0.321484 0.511984)
							(end -0.381 0.3683)
						)
						(arc
							(start -0.381 -0.3683)
							(mid -0.321484 -0.511984)
							(end -0.1778 -0.5715)
						)
						(arc
							(start 0.1778 -0.5715)
							(mid 0.321484 -0.511984)
							(end 0.381 -0.3683)
						)
						(arc
							(start 0.381 0.3683)
							(mid 0.321484 0.511984)
							(end 0.1778 0.5715)
						)
					)
					(width 0)
					(fill yes)
				)
			)
		)
		(pad "S" smd custom
			(at 0.98425 0.9525 180)
			(size 0.1905 0.1905)
			(layers "F.Cu" "F.Mask" "F.Paste")
			(net "GND")
			(options
				(clearance outline)
				(anchor circle)
			)
			(primitives
				(gr_poly
					(pts
						(arc
							(start -0.1778 0.5715)
							(mid -0.321484 0.511984)
							(end -0.381 0.3683)
						)
						(arc
							(start -0.381 -0.3683)
							(mid -0.321484 -0.511984)
							(end -0.1778 -0.5715)
						)
						(arc
							(start 0.1778 -0.5715)
							(mid 0.321484 -0.511984)
							(end 0.381 -0.3683)
						)
						(arc
							(start 0.381 0.3683)
							(mid 0.321484 0.511984)
							(end 0.1778 0.5715)
						)
					)
					(width 0)
					(fill yes)
				)
			)
		)
	)
	(footprint ""
		(layer "F.Cu")
		(at 394.56995 -303.954942 180)
		(property "Reference" "C150"
			(at 0 0 180)
			(layer "F.SilkS")
			(hide yes)
			(effects
				(font
					(size 1.27 1.27)
				)
			)
		)
		(property "Value" "SC4D7U25V5KX-1-GP"
			(at -0.0762 -6.1214 180)
			(unlocked yes)
			(layer "F.Fab")
			(hide yes)
			(effects
				(font
					(size 1.016 1.016)
					(thickness 0.1524)
				)
			)
		)
		(property "Device Type" "C805H58"
			(at -0.0762 -8.1534 180)
			(unlocked yes)
			(layer "F.Fab")
			(hide yes)
			(effects
				(font
					(size 1.016 1.016)
					(thickness 0.1524)
				)
			)
		)
		(duplicate_pad_numbers_are_jumpers no)
		(fp_line
			(start 0.635 0)
			(end -0.635 0)
			(stroke
				(width 0.508)
				(type default)
			)
			(layer "F.SilkS")
		)
		(fp_rect
			(start -0.9652 1.778)
			(end 0.9652 -1.778)
			(stroke
				(width 0)
				(type default)
			)
			(fill no)
			(layer "F.CrtYd")
		)
		(fp_poly
			(pts
				(xy -0.9652 -1.778) (xy 0.9652 -1.778) (xy 0.9652 1.778) (xy -0.9652 1.778)
			)
			(stroke
				(width 0)
				(type default)
			)
			(fill no)
			(layer "F.Fab")
		)
		(pad "1" smd rect
			(at 0 -0.9652 180)
			(size 1.397 1.143)
			(layers "F.Cu" "F.Mask" "F.Paste")
			(net "P12V_HDD8")
		)
		(pad "2" smd rect
			(at 0 0.9652 180)
			(size 1.397 1.143)
			(layers "F.Cu" "F.Mask" "F.Paste")
			(net "GND")
		)
	)
)
